# BASEBOARD_FAB2 (Tioga Pass) — schematic netlist excerpt (pin names and nets, part order shuffled) for the footprints in the layout excerpt that follows; sources: Cadence DE-HDL packaged netlist, KiCad conversion of Wiwynn_Tioga_Pass_MB.brd

C5G108  CAP_A  22.0UF 4V 20% X6S  pkg 0603V  page 243 : A = PVDDQ_KLM ; B = GND
R25W58  18KR2F-GP  1%  pkg RCL_GP  page 144 : \1\ = A_DACRSET ; \2\ = GND
C2L2  CAP  220PF 50V 10% X7R  pkg 0402LF  page 235 : A = VR_P1V05_PCH_STBY_AVSP ; B = VSENSE_P1V05_PCH_STBY_AVSN

(kicad_pcb
	(version 20260206)
	(generator "pcbnew")
	(generator_version "10.0")
	(general
		(thickness 1.6)
		(legacy_teardrops no)
	)
	(paper "A4")
	(title_block
		(title "Wiwynn_Tioga_Pass_MB.brd")
		(comment 1 "Tioga Pass / footprints 3240-3242 of 4770")
	)
	(layers
		(0 "F.Cu" signal "TOP")
		(4 "In1.Cu" signal "L2GND")
		(6 "In2.Cu" signal "L3")
		(8 "In3.Cu" signal "L4GND")
		(10 "In4.Cu" signal "L5")
		(12 "In5.Cu" signal "L6GND")
		(14 "In6.Cu" signal "L7VCC")
		(16 "In7.Cu" signal "L8VCC")
		(18 "In8.Cu" signal "L9GND")
		(20 "In9.Cu" signal "L10")
		(22 "In10.Cu" signal "L11GND")
		(24 "In11.Cu" signal "L12")
		(26 "In12.Cu" signal "L13GND")
		(2 "B.Cu" signal "BOTTOM")
		(9 "F.Adhes" user "F.Adhesive")
		(11 "B.Adhes" user "B.Adhesive")
		(13 "F.Paste" user "Package Geometry/Pastemask Top")
		(15 "B.Paste" user "Package Geometry/Pastemask Bottom")
		(5 "F.SilkS" user "Ref Des/Silkscreen Top")
		(7 "B.SilkS" user "Ref Des/Silkscreen Bottom")
		(1 "F.Mask" user "Board Geometry/Soldermask Top")
		(3 "B.Mask" user "Board Geometry/Soldermask Bottom")
		(17 "Dwgs.User" user "User.Drawings")
		(19 "Cmts.User" user "User.Comments")
		(21 "Eco1.User" user "User.Eco1")
		(23 "Eco2.User" user "User.Eco2")
		(25 "Edge.Cuts" user "Board Geometry/Outline")
		(27 "Margin" user)
		(31 "F.CrtYd" user "Package Geometry/Place Bound Top")
		(29 "B.CrtYd" user "Package Geometry/Place Bound Bottom")
		(35 "F.Fab" user "Ref Des/Assembly Top")
		(33 "B.Fab" user "Ref Des/Assembly Bottom")
	)
	(footprint ""
		(layer "B.Cu")
		(at 394.35405 -157.226 -90)
		(property "Reference" "C2L2"
			(at 0 0 90)
			(layer "B.SilkS")
			(hide yes)
			(effects
				(font
					(size 1.27 1.27)
				)
				(justify mirror)
			)
		)
		(property "Value" ""
			(at 0 0 90)
			(layer "B.Fab")
			(effects
				(font
					(size 1.27 1.27)
				)
				(justify mirror)
			)
		)
		(duplicate_pad_numbers_are_jumpers no)
		(fp_poly
			(pts
				(xy -0.3048 -0.1016) (xy -0.3048 0.9906) (xy 0.3048 0.9906) (xy 0.3048 -0.1016)
			)
			(stroke
				(width 0)
				(type default)
			)
			(fill no)
			(layer "B.CrtYd")
		)
		(fp_line
			(start -0.3048 0.9906)
			(end -0.3048 -0.1016)
			(stroke
				(width 0.1)
				(type default)
			)
			(layer "B.Fab")
		)
		(fp_line
			(start 0.3048 0.9906)
			(end -0.3048 0.9906)
			(stroke
				(width 0.1)
				(type default)
			)
			(layer "B.Fab")
		)
		(fp_line
			(start -0.3048 -0.1016)
			(end 0.3048 -0.1016)
			(stroke
				(width 0.1)
				(type default)
			)
			(layer "B.Fab")
		)
		(fp_line
			(start 0.3048 -0.1016)
			(end 0.3048 0.9906)
			(stroke
				(width 0.1)
				(type default)
			)
			(layer "B.Fab")
		)
		(pad "1" smd rect
			(at 0 0 90)
			(size 0.508 0.508)
			(layers "B.Cu" "B.Mask" "B.Paste")
			(net "VR_P1V05_PCH_STBY_AVSP")
		)
		(pad "2" smd rect
			(at 0 0.889 90)
			(size 0.508 0.508)
			(layers "B.Cu" "B.Mask" "B.Paste")
			(net "VSENSE_P1V05_PCH_STBY_AVSN")
		)
		(zone
			(layer "B.Cu")
			(hatch none 0.5)
			(connect_pads
				(clearance 0)
			)
			(min_thickness 0.25)
			(keepout
				(tracks not_allowed)
				(vias allowed)
				(pads allowed)
				(copperpour not_allowed)
				(footprints allowed)
			)
			(placement
				(enabled no)
				(sheetname "")
			)
			(fill
				(thermal_gap 0.5)
				(thermal_bridge_width 0.5)
				(island_removal_mode 0)
			)
			(polygon
				(pts
					(xy 393.71905 -156.972) (xy 393.71905 -157.48) (xy 394.10005 -157.48) (xy 394.10005 -156.972)
				)
			)
		)
		(zone
			(layer "B.Cu")
			(hatch none 0.5)
			(connect_pads
				(clearance 0)
			)
			(min_thickness 0.25)
			(keepout
				(tracks allowed)
				(vias not_allowed)
				(pads allowed)
				(copperpour not_allowed)
				(footprints allowed)
			)
			(placement
				(enabled no)
				(sheetname "")
			)
			(fill
				(thermal_gap 0.5)
				(thermal_bridge_width 0.5)
				(island_removal_mode 0)
			)
			(polygon
				(pts
					(xy 394.10005 -156.972) (xy 394.10005 -157.48) (xy 393.71905 -157.48) (xy 393.71905 -156.972)
				)
			)
		)
	)
	(footprint ""
		(layer "B.Cu")
		(at 423.672 -21.59 90)
		(property "Reference" "R25W58"
			(at 0 0 90)
			(layer "B.SilkS")
			(hide yes)
			(effects
				(font
					(size 1.27 1.27)
				)
				(justify mirror)
			)
		)
		(property "Value" "*"
			(at -0.064008 -4.108196 90)
			(unlocked yes)
			(layer "B.Fab")
			(hide yes)
			(effects
				(font
					(size 1.27 1.016)
					(thickness 0.1524)
				)
				(justify mirror)
			)
		)
		(property "Device Type" "18KR2F-GP_RCL_GP-18KR2F-GP,64.A"
			(at -0.064008 -5.632196 90)
			(unlocked yes)
			(layer "B.Fab")
			(hide yes)
			(effects
				(font
					(size 1.27 1.016)
					(thickness 0.1524)
				)
				(justify mirror)
			)
		)
		(duplicate_pad_numbers_are_jumpers no)
		(fp_line
			(start 0.508 -0.9398)
			(end 0.508 0.9398)
			(stroke
				(width 0.1524)
				(type default)
			)
			(layer "B.SilkS")
		)
		(fp_line
			(start -0.508 -0.9398)
			(end 0.508 -0.9398)
			(stroke
				(width 0.1524)
				(type default)
			)
			(layer "B.SilkS")
		)
		(fp_rect
			(start 0.508 0.9398)
			(end -0.508 -0.9398)
			(stroke
				(width 0)
				(type default)
			)
			(fill no)
			(layer "B.CrtYd")
		)
		(fp_rect
			(start 0.508 0.9398)
			(end -0.508 -0.9398)
			(stroke
				(width 0)
				(type default)
			)
			(fill no)
			(layer "B.Fab")
		)
		(pad "1" smd custom
			(at 0 -0.4445 270)
			(size 0.1397 0.1397)
			(layers "B.Cu" "B.Mask" "B.Paste")
			(net "A_DACRSET")
			(options
				(clearance outline)
				(anchor circle)
			)
			(primitives
				(gr_poly
					(pts
						(arc
							(start -0.1778 0.2794)
							(mid -0.249642 0.249642)
							(end -0.2794 0.1778)
						)
						(arc
							(start -0.2794 -0.1778)
							(mid -0.249642 -0.249642)
							(end -0.1778 -0.2794)
						)
						(arc
							(start 0.1778 -0.2794)
							(mid 0.249642 -0.249642)
							(end 0.2794 -0.1778)
						)
						(arc
							(start 0.2794 0.1778)
							(mid 0.249642 0.249642)
							(end 0.1778 0.2794)
						)
					)
					(width 0)
					(fill yes)
				)
			)
		)
		(pad "2" smd custom
			(at 0 0.4445 270)
			(size 0.1397 0.1397)
			(layers "B.Cu" "B.Mask" "B.Paste")
			(net "GND")
			(options
				(clearance outline)
				(anchor circle)
			)
			(primitives
				(gr_poly
					(pts
						(arc
							(start -0.1778 0.2794)
							(mid -0.249642 0.249642)
							(end -0.2794 0.1778)
						)
						(arc
							(start -0.2794 -0.1778)
							(mid -0.249642 -0.249642)
							(end -0.1778 -0.2794)
						)
						(arc
							(start 0.1778 -0.2794)
							(mid 0.249642 -0.249642)
							(end 0.2794 -0.1778)
						)
						(arc
							(start 0.2794 0.1778)
							(mid 0.249642 0.249642)
							(end 0.1778 0.2794)
						)
					)
					(width 0)
					(fill yes)
				)
			)
		)
	)
	(footprint ""
		(layer "B.Cu")
		(at 107.8611 -140.208 90)
		(property "Reference" "C5G108"
			(at -1.14681 0.76708 180)
			(unlocked yes)
			(layer "B.SilkS")
			(effects
				(font
					(size 0.7874 0.5842)
					(thickness 0.1524)
				)
				(justify mirror)
			)
		)
		(property "Value" ""
			(at 0 0 90)
			(layer "B.Fab")
			(effects
				(font
					(size 1.27 1.27)
				)
				(justify mirror)
			)
		)
		(duplicate_pad_numbers_are_jumpers no)
		(fp_rect
			(start -0.4953 -0.2032)
			(end 0.4953 1.6002)
			(stroke
				(width 0)
				(type default)
			)
			(fill no)
			(layer "B.CrtYd")
		)
		(fp_line
			(start 0.4953 -0.2032)
			(end -0.4953 -0.2032)
			(stroke
				(width 0.1)
				(type default)
			)
			(layer "B.Fab")
		)
		(fp_line
			(start -0.4953 -0.2032)
			(end -0.4953 1.6002)
			(stroke
				(width 0.1)
				(type default)
			)
			(layer "B.Fab")
		)
		(fp_line
			(start 0.4953 1.6002)
			(end 0.4953 -0.2032)
			(stroke
				(width 0.1)
				(type default)
			)
			(layer "B.Fab")
		)
		(fp_line
			(start -0.4953 1.6002)
			(end 0.4953 1.6002)
			(stroke
				(width 0.1)
				(type default)
			)
			(layer "B.Fab")
		)
		(pad "1" smd rect
			(at 0 0 270)
			(size 0.762 0.889)
			(layers "B.Cu" "B.Mask" "B.Paste")
			(net "PVDDQ_KLM")
		)
		(pad "2" smd rect
			(at 0 1.397 270)
			(size 0.762 0.889)
			(layers "B.Cu" "B.Mask" "B.Paste")
			(net "GND")
		)
		(zone
			(layer "B.Cu")
			(hatch none 0.5)
			(connect_pads
				(clearance 0)
			)
			(min_thickness 0.25)
			(keepout
				(tracks not_allowed)
				(vias allowed)
				(pads allowed)
				(copperpour not_allowed)
				(footprints allowed)
			)
			(placement
				(enabled no)
				(sheetname "")
			)
			(fill
				(thermal_gap 0.5)
				(thermal_bridge_width 0.5)
				(island_removal_mode 0)
			)
			(polygon
				(pts
					(xy 108.3056 -139.827) (xy 108.8136 -139.827) (xy 108.8136 -140.589) (xy 108.3056 -140.589)
				)
			)
		)
	)
)
